FILE_TYPE = MACRO_DRAWING;
SET COLOR_WIRE YELLOW;
SET COLOR_PROP ORANGE;
SET COLOR_DOT WHITE;
SET COLOR_ARC YELLOW;
SET COLOR_BODY GREEN;
SET COLOR_NOTE PURPLE;
SET PROP_DISPLAY VALUE;
SET PAGE_NUMBER P417;
FORCEADD PT5161LRS..1
(-7525 3800);
FORCEPROP 1 LAST LOCATION U6012
J 0
(-7875 5425);
DISPLAY 0.723404 (-7875 5425);
PAINT GREEN (-7875 5425);
FORCEPROP 0 LAST $SEC 1
J 0
(-7875 5575);
DISPLAY 0.680851 (-7875 5575);
PAINT MONO (-7875 5575);
DISPLAY INVISIBLE (-7875 5575);
FORCEPROP 0 LAST CDS_SEC 1
J 0
(-7875 5575);
DISPLAY 0.680851 (-7875 5575);
DISPLAY INVISIBLE (-7875 5575);
FORCEPROP 0 LASTPIN (-7075 4950) $PN N2
J 0
(-7065 4960);
DISPLAY 0.680851 (-7065 4960);
PAINT MONO (-7065 4960);
FORCEPROP 0 LASTPIN (-7075 4600) $PN Y2
J 0
(-7065 4610);
DISPLAY 0.680851 (-7065 4610);
PAINT MONO (-7065 4610);
FORCEPROP 0 LASTPIN (-7075 4250) $PN AG2
J 0
(-7065 4260);
DISPLAY 0.680851 (-7065 4260);
PAINT MONO (-7065 4260);
FORCEPROP 0 LASTPIN (-7075 3900) $PN AP2
J 0
(-7065 3910);
DISPLAY 0.680851 (-7065 3910);
PAINT MONO (-7065 3910);
FORCEPROP 0 LASTPIN (-7075 3550) $PN BA2
J 0
(-7065 3560);
DISPLAY 0.680851 (-7065 3560);
PAINT MONO (-7065 3560);
FORCEPROP 0 LASTPIN (-7075 3200) $PN BH2
J 0
(-7065 3210);
DISPLAY 0.680851 (-7065 3210);
PAINT MONO (-7065 3210);
FORCEPROP 0 LASTPIN (-7075 2850) $PN BR2
J 0
(-7065 2860);
DISPLAY 0.680851 (-7065 2860);
PAINT MONO (-7065 2860);
FORCEPROP 0 LASTPIN (-7075 2500) $PN CB2
J 0
(-7065 2510);
DISPLAY 0.680851 (-7065 2510);
PAINT MONO (-7065 2510);
FORCEPROP 0 LASTPIN (-7075 5050) $PN R1
J 0
(-7065 5060);
DISPLAY 0.680851 (-7065 5060);
PAINT MONO (-7065 5060);
FORCEPROP 0 LASTPIN (-7075 4700) $PN AB1
J 0
(-7065 4710);
DISPLAY 0.680851 (-7065 4710);
PAINT MONO (-7065 4710);
FORCEPROP 0 LASTPIN (-7075 4350) $PN AJ1
J 0
(-7065 4360);
DISPLAY 0.680851 (-7065 4360);
PAINT MONO (-7065 4360);
FORCEPROP 0 LASTPIN (-7075 4000) $PN AT1
J 0
(-7065 4010);
DISPLAY 0.680851 (-7065 4010);
PAINT MONO (-7065 4010);
FORCEPROP 0 LASTPIN (-7075 3650) $PN BC1
J 0
(-7065 3660);
DISPLAY 0.680851 (-7065 3660);
PAINT MONO (-7065 3660);
FORCEPROP 0 LASTPIN (-7075 3300) $PN BK1
J 0
(-7065 3310);
DISPLAY 0.680851 (-7065 3310);
PAINT MONO (-7065 3310);
FORCEPROP 0 LASTPIN (-7075 2950) $PN BU1
J 0
(-7065 2960);
DISPLAY 0.680851 (-7065 2960);
PAINT MONO (-7065 2960);
FORCEPROP 0 LASTPIN (-7075 2600) $PN CD1
J 0
(-7065 2610);
DISPLAY 0.680851 (-7065 2610);
PAINT MONO (-7065 2610);
FORCEPROP 1 LAST MATERIAL IC
J 0
(-7875 5275);
DISPLAY 0.723404 (-7875 5275);
PAINT GREEN (-7875 5275);
FORCEPROP 2 LAST PART_TYPE SMLF
J 0
(-7875 5525);
DISPLAY 0.680851 (-7875 5525);
FORCEPROP 2 LAST VALUE PT5161LRS
J 0
(-7875 5475);
DISPLAY 0.680851 (-7875 5475);
FORCEPROP 2 LAST CDS_LIB pure_quanta
J 0
(-7525 3800);
DISPLAY INVISIBLE (-7525 3800);
FORCEPROP 1 LAST CDS_LMAN_SYM_OUTLINE -350,1450,300,-1400
J 0
(-7525 3800);
DISPLAY 0.468085 (-7525 3800);
PAINT GREEN (-7525 3800);
DISPLAY INVISIBLE (-7525 3800);
FORCEPROP 1 LAST NEEDS_NO_SIZE TRUE
J 0
(-7525 3800);
DISPLAY 0.723404 (-7525 3800);
PAINT GREEN (-7525 3800);
DISPLAY INVISIBLE (-7525 3800);
FORCEPROP 1 LAST PATH I1
J 0
(-7525 3800);
DISPLAY 0.723404 (-7525 3800);
PAINT GREEN (-7525 3800);
DISPLAY INVISIBLE (-7525 3800);
FORCEPROP 1 LAST PART_NUMBER AJ051610U03
J 0
(-7875 5350);
DISPLAY 0.723404 (-7875 5350);
PAINT GREEN (-7875 5350);
DISPLAY INVISIBLE (-7875 5350);
FORCEADD TAP..1
(-6500 4000);
FORCEPROP 3 LASTPIN (-6550 4000) SIG_NAME P5E_CPU0_P2_RX_BUF_DP<12>
J 0
(-6540 4010);
DISPLAY 0.659574 (-6540 4010);
PAINT MONO (-6540 4010);
DISPLAY INVISIBLE (-6540 4010);
FORCEPROP 1 LASTPIN (-6550 4000) BN 12
J 0
(-6562 4008);
DISPLAY 0.680851 (-6562 4008);
PAINT GREEN (-6562 4008);
FORCEPROP 2 LAST CDS_LIB standard
J 0
(-6500 4000);
DISPLAY INVISIBLE (-6500 4000);
FORCEPROP 1 LAST BODY_TYPE PLUMBING
J 0
(-6500 4050);
DISPLAY 0.872340 (-6500 4050);
PAINT GREEN (-6500 4050);
DISPLAY INVISIBLE (-6500 4050);
FORCEPROP 1 LAST HDL_TAP TRUE
J 0
(-6175 3875);
DISPLAY 0.872340 (-6175 3875);
DISPLAY INVISIBLE (-6175 3875);
FORCEPROP 1 LAST PATH I10
J 0
(-6502 4000);
DISPLAY 0.872340 (-6502 4000);
PAINT GREEN (-6502 4000);
DISPLAY INVISIBLE (-6502 4000);
FORCEADD TAP..1
(-6300 3900);
FORCEPROP 3 LASTPIN (-6350 3900) SIG_NAME P5E_CPU0_P2_RX_BUF_DN<12>
J 0
(-6340 3910);
DISPLAY 0.659574 (-6340 3910);
PAINT MONO (-6340 3910);
DISPLAY INVISIBLE (-6340 3910);
FORCEPROP 1 LASTPIN (-6350 3900) BN 12
J 0
(-6362 3908);
DISPLAY 0.680851 (-6362 3908);
PAINT GREEN (-6362 3908);
FORCEPROP 2 LAST CDS_LIB standard
J 0
(-6300 3900);
DISPLAY INVISIBLE (-6300 3900);
FORCEPROP 1 LAST BODY_TYPE PLUMBING
J 0
(-6300 3950);
DISPLAY 0.872340 (-6300 3950);
PAINT GREEN (-6300 3950);
DISPLAY INVISIBLE (-6300 3950);
FORCEPROP 1 LAST HDL_TAP TRUE
J 0
(-5975 3775);
DISPLAY 0.872340 (-5975 3775);
DISPLAY INVISIBLE (-5975 3775);
FORCEPROP 1 LAST PATH I11
J 0
(-6302 3900);
DISPLAY 0.872340 (-6302 3900);
PAINT GREEN (-6302 3900);
DISPLAY INVISIBLE (-6302 3900);
FORCEADD TAP..1
(-6300 4250);
FORCEPROP 3 LASTPIN (-6350 4250) SIG_NAME P5E_CPU0_P2_RX_BUF_DN<13>
J 0
(-6340 4260);
DISPLAY 0.659574 (-6340 4260);
PAINT MONO (-6340 4260);
DISPLAY INVISIBLE (-6340 4260);
FORCEPROP 1 LASTPIN (-6350 4250) BN 13
J 0
(-6362 4258);
DISPLAY 0.680851 (-6362 4258);
PAINT GREEN (-6362 4258);
FORCEPROP 2 LAST CDS_LIB standard
J 0
(-6300 4250);
DISPLAY INVISIBLE (-6300 4250);
FORCEPROP 1 LAST BODY_TYPE PLUMBING
J 0
(-6300 4300);
DISPLAY 0.872340 (-6300 4300);
PAINT GREEN (-6300 4300);
DISPLAY INVISIBLE (-6300 4300);
FORCEPROP 1 LAST HDL_TAP TRUE
J 0
(-5975 4125);
DISPLAY 0.872340 (-5975 4125);
DISPLAY INVISIBLE (-5975 4125);
FORCEPROP 1 LAST PATH I12
J 0
(-6302 4250);
DISPLAY 0.872340 (-6302 4250);
PAINT GREEN (-6302 4250);
DISPLAY INVISIBLE (-6302 4250);
FORCEADD TAP..1
(-6500 4350);
FORCEPROP 3 LASTPIN (-6550 4350) SIG_NAME P5E_CPU0_P2_RX_BUF_DP<13>
J 0
(-6540 4360);
DISPLAY 0.659574 (-6540 4360);
PAINT MONO (-6540 4360);
DISPLAY INVISIBLE (-6540 4360);
FORCEPROP 1 LASTPIN (-6550 4350) BN 13
J 0
(-6562 4358);
DISPLAY 0.680851 (-6562 4358);
PAINT GREEN (-6562 4358);
FORCEPROP 2 LAST CDS_LIB standard
J 0
(-6500 4350);
DISPLAY INVISIBLE (-6500 4350);
FORCEPROP 1 LAST BODY_TYPE PLUMBING
J 0
(-6500 4400);
DISPLAY 0.872340 (-6500 4400);
PAINT GREEN (-6500 4400);
DISPLAY INVISIBLE (-6500 4400);
FORCEPROP 1 LAST HDL_TAP TRUE
J 0
(-6175 4225);
DISPLAY 0.872340 (-6175 4225);
DISPLAY INVISIBLE (-6175 4225);
FORCEPROP 1 LAST PATH I13
J 0
(-6502 4350);
DISPLAY 0.872340 (-6502 4350);
PAINT GREEN (-6502 4350);
DISPLAY INVISIBLE (-6502 4350);
FORCEADD TAP..1
(-6500 4700);
FORCEPROP 3 LASTPIN (-6550 4700) SIG_NAME P5E_CPU0_P2_RX_BUF_DP<14>
J 0
(-6540 4710);
DISPLAY 0.659574 (-6540 4710);
PAINT MONO (-6540 4710);
DISPLAY INVISIBLE (-6540 4710);
FORCEPROP 1 LASTPIN (-6550 4700) BN 14
J 0
(-6562 4708);
DISPLAY 0.680851 (-6562 4708);
PAINT GREEN (-6562 4708);
FORCEPROP 2 LAST CDS_LIB standard
J 0
(-6500 4700);
DISPLAY INVISIBLE (-6500 4700);
FORCEPROP 1 LAST BODY_TYPE PLUMBING
J 0
(-6500 4750);
DISPLAY 0.872340 (-6500 4750);
PAINT GREEN (-6500 4750);
DISPLAY INVISIBLE (-6500 4750);
FORCEPROP 1 LAST HDL_TAP TRUE
J 0
(-6175 4575);
DISPLAY 0.872340 (-6175 4575);
DISPLAY INVISIBLE (-6175 4575);
FORCEPROP 1 LAST PATH I14
J 0
(-6502 4700);
DISPLAY 0.872340 (-6502 4700);
PAINT GREEN (-6502 4700);
DISPLAY INVISIBLE (-6502 4700);
FORCEADD TAP..1
(-6300 4600);
FORCEPROP 3 LASTPIN (-6350 4600) SIG_NAME P5E_CPU0_P2_RX_BUF_DN<14>
J 0
(-6340 4610);
DISPLAY 0.659574 (-6340 4610);
PAINT MONO (-6340 4610);
DISPLAY INVISIBLE (-6340 4610);
FORCEPROP 1 LASTPIN (-6350 4600) BN 14
J 0
(-6362 4608);
DISPLAY 0.680851 (-6362 4608);
PAINT GREEN (-6362 4608);
FORCEPROP 2 LAST CDS_LIB standard
J 0
(-6300 4600);
DISPLAY INVISIBLE (-6300 4600);
FORCEPROP 1 LAST BODY_TYPE PLUMBING
J 0
(-6300 4650);
DISPLAY 0.872340 (-6300 4650);
PAINT GREEN (-6300 4650);
DISPLAY INVISIBLE (-6300 4650);
FORCEPROP 1 LAST HDL_TAP TRUE
J 0
(-5975 4475);
DISPLAY 0.872340 (-5975 4475);
DISPLAY INVISIBLE (-5975 4475);
FORCEPROP 1 LAST PATH I15
J 0
(-6302 4600);
DISPLAY 0.872340 (-6302 4600);
PAINT GREEN (-6302 4600);
DISPLAY INVISIBLE (-6302 4600);
FORCEADD TAP..1
(-6300 4950);
FORCEPROP 3 LASTPIN (-6350 4950) SIG_NAME P5E_CPU0_P2_RX_BUF_DN<15>
J 0
(-6340 4960);
DISPLAY 0.659574 (-6340 4960);
PAINT MONO (-6340 4960);
DISPLAY INVISIBLE (-6340 4960);
FORCEPROP 1 LASTPIN (-6350 4950) BN 15
J 0
(-6362 4958);
DISPLAY 0.680851 (-6362 4958);
PAINT GREEN (-6362 4958);
FORCEPROP 2 LAST CDS_LIB standard
J 0
(-6300 4950);
DISPLAY INVISIBLE (-6300 4950);
FORCEPROP 1 LAST BODY_TYPE PLUMBING
J 0
(-6300 5000);
DISPLAY 0.872340 (-6300 5000);
PAINT GREEN (-6300 5000);
DISPLAY INVISIBLE (-6300 5000);
FORCEPROP 1 LAST HDL_TAP TRUE
J 0
(-5975 4825);
DISPLAY 0.872340 (-5975 4825);
DISPLAY INVISIBLE (-5975 4825);
FORCEPROP 1 LAST PATH I16
J 0
(-6302 4950);
DISPLAY 0.872340 (-6302 4950);
PAINT GREEN (-6302 4950);
DISPLAY INVISIBLE (-6302 4950);
FORCEADD TAP..1
(-6500 5050);
FORCEPROP 3 LASTPIN (-6550 5050) SIG_NAME P5E_CPU0_P2_RX_BUF_DP<15>
J 0
(-6540 5060);
DISPLAY 0.659574 (-6540 5060);
PAINT MONO (-6540 5060);
DISPLAY INVISIBLE (-6540 5060);
FORCEPROP 1 LASTPIN (-6550 5050) BN 15
J 0
(-6562 5058);
DISPLAY 0.680851 (-6562 5058);
PAINT GREEN (-6562 5058);
FORCEPROP 2 LAST CDS_LIB standard
J 0
(-6500 5050);
DISPLAY INVISIBLE (-6500 5050);
FORCEPROP 1 LAST BODY_TYPE PLUMBING
J 0
(-6500 5100);
DISPLAY 0.872340 (-6500 5100);
PAINT GREEN (-6500 5100);
DISPLAY INVISIBLE (-6500 5100);
FORCEPROP 1 LAST HDL_TAP TRUE
J 0
(-6175 4925);
DISPLAY 0.872340 (-6175 4925);
DISPLAY INVISIBLE (-6175 4925);
FORCEPROP 1 LAST PATH I17
J 0
(-6502 5050);
DISPLAY 0.872340 (-6502 5050);
PAINT GREEN (-6502 5050);
DISPLAY INVISIBLE (-6502 5050);
FORCEADD OFFPAGE..1
R 2
(-5275 5150);
FORCEPROP 2 LAST $XR0 115 
J 0
(-5089 5150);
DISPLAY 0.638298 (-5089 5150);
PAINT MONO (-5089 5150);
FORCEPROP 2 LAST CDS_LIB standard
J 0
(-5275 5150);
DISPLAY INVISIBLE (-5275 5150);
FORCEPROP 1 LAST OFFPAGE TRUE
J 2
(-5600 5025);
DISPLAY 0.872340 (-5600 5025);
DISPLAY INVISIBLE (-5600 5025);
FORCEPROP 1 LAST COMMENT_BODY TRUE
J 2
(-5400 5050);
DISPLAY 0.872340 (-5400 5050);
PAINT GREEN (-5400 5050);
DISPLAY INVISIBLE (-5400 5050);
FORCEPROP 2 LAST PATH I18
J 0
(-5100 5225);
DISPLAY 0.680851 (-5100 5225);
DISPLAY INVISIBLE (-5100 5225);
FORCEADD OFFPAGE..1
R 2
(-5275 5075);
FORCEPROP 2 LAST $XR0 115 
J 0
(-5089 5075);
DISPLAY 0.638298 (-5089 5075);
PAINT MONO (-5089 5075);
FORCEPROP 2 LAST CDS_LIB standard
J 0
(-5275 5075);
DISPLAY INVISIBLE (-5275 5075);
FORCEPROP 1 LAST OFFPAGE TRUE
J 2
(-5600 4950);
DISPLAY 0.872340 (-5600 4950);
DISPLAY INVISIBLE (-5600 4950);
FORCEPROP 1 LAST COMMENT_BODY TRUE
J 2
(-5400 4975);
DISPLAY 0.872340 (-5400 4975);
PAINT GREEN (-5400 4975);
DISPLAY INVISIBLE (-5400 4975);
FORCEPROP 2 LAST PATH I19
J 0
(-5100 5150);
DISPLAY 0.680851 (-5100 5150);
DISPLAY INVISIBLE (-5100 5150);
FORCEADD TAP..1
(-6500 2600);
FORCEPROP 3 LASTPIN (-6550 2600) SIG_NAME P5E_CPU0_P2_RX_BUF_DP<8>
J 0
(-6540 2610);
DISPLAY 0.659574 (-6540 2610);
PAINT MONO (-6540 2610);
DISPLAY INVISIBLE (-6540 2610);
FORCEPROP 1 LASTPIN (-6550 2600) BN 8
J 0
(-6562 2608);
DISPLAY 0.680851 (-6562 2608);
PAINT GREEN (-6562 2608);
FORCEPROP 2 LAST CDS_LIB standard
J 0
(-6500 2600);
DISPLAY INVISIBLE (-6500 2600);
FORCEPROP 1 LAST BODY_TYPE PLUMBING
J 0
(-6500 2650);
DISPLAY 0.872340 (-6500 2650);
PAINT GREEN (-6500 2650);
DISPLAY INVISIBLE (-6500 2650);
FORCEPROP 1 LAST HDL_TAP TRUE
J 0
(-6175 2475);
DISPLAY 0.872340 (-6175 2475);
DISPLAY INVISIBLE (-6175 2475);
FORCEPROP 1 LAST PATH I2
J 0
(-6502 2600);
DISPLAY 0.872340 (-6502 2600);
PAINT GREEN (-6502 2600);
DISPLAY INVISIBLE (-6502 2600);
FORCEADD TAP..1
(-2050 2625);
FORCEPROP 3 LASTPIN (-2100 2625) SIG_NAME P5E_CPU0_P2_RX_BUF_DP<0>
J 0
(-2090 2635);
DISPLAY 0.659574 (-2090 2635);
PAINT MONO (-2090 2635);
DISPLAY INVISIBLE (-2090 2635);
FORCEPROP 1 LASTPIN (-2100 2625) BN 0
J 0
(-2112 2633);
DISPLAY 0.680851 (-2112 2633);
PAINT GREEN (-2112 2633);
FORCEPROP 2 LAST CDS_LIB standard
J 0
(-2050 2625);
DISPLAY INVISIBLE (-2050 2625);
FORCEPROP 1 LAST BODY_TYPE PLUMBING
J 0
(-2050 2675);
DISPLAY 0.872340 (-2050 2675);
PAINT GREEN (-2050 2675);
DISPLAY INVISIBLE (-2050 2675);
FORCEPROP 1 LAST HDL_TAP TRUE
J 0
(-1725 2500);
DISPLAY 0.872340 (-1725 2500);
DISPLAY INVISIBLE (-1725 2500);
FORCEPROP 1 LAST PATH I20
J 0
(-2052 2625);
DISPLAY 0.872340 (-2052 2625);
PAINT GREEN (-2052 2625);
DISPLAY INVISIBLE (-2052 2625);
FORCEADD TAP..1
(-1850 2525);
FORCEPROP 3 LASTPIN (-1900 2525) SIG_NAME P5E_CPU0_P2_RX_BUF_DN<0>
J 0
(-1890 2535);
DISPLAY 0.659574 (-1890 2535);
PAINT MONO (-1890 2535);
DISPLAY INVISIBLE (-1890 2535);
FORCEPROP 1 LASTPIN (-1900 2525) BN 0
J 0
(-1912 2533);
DISPLAY 0.680851 (-1912 2533);
PAINT GREEN (-1912 2533);
FORCEPROP 2 LAST CDS_LIB standard
J 0
(-1850 2525);
DISPLAY INVISIBLE (-1850 2525);
FORCEPROP 1 LAST BODY_TYPE PLUMBING
J 0
(-1850 2575);
DISPLAY 0.872340 (-1850 2575);
PAINT GREEN (-1850 2575);
DISPLAY INVISIBLE (-1850 2575);
FORCEPROP 1 LAST HDL_TAP TRUE
J 0
(-1525 2400);
DISPLAY 0.872340 (-1525 2400);
DISPLAY INVISIBLE (-1525 2400);
FORCEPROP 1 LAST PATH I21
J 0
(-1852 2525);
DISPLAY 0.872340 (-1852 2525);
PAINT GREEN (-1852 2525);
DISPLAY INVISIBLE (-1852 2525);
FORCEADD TAP..1
(-2050 2975);
FORCEPROP 3 LASTPIN (-2100 2975) SIG_NAME P5E_CPU0_P2_RX_BUF_DP<1>
J 0
(-2090 2985);
DISPLAY 0.659574 (-2090 2985);
PAINT MONO (-2090 2985);
DISPLAY INVISIBLE (-2090 2985);
FORCEPROP 1 LASTPIN (-2100 2975) BN 1
J 0
(-2112 2983);
DISPLAY 0.680851 (-2112 2983);
PAINT GREEN (-2112 2983);
FORCEPROP 2 LAST CDS_LIB standard
J 0
(-2050 2975);
DISPLAY INVISIBLE (-2050 2975);
FORCEPROP 1 LAST BODY_TYPE PLUMBING
J 0
(-2050 3025);
DISPLAY 0.872340 (-2050 3025);
PAINT GREEN (-2050 3025);
DISPLAY INVISIBLE (-2050 3025);
FORCEPROP 1 LAST HDL_TAP TRUE
J 0
(-1725 2850);
DISPLAY 0.872340 (-1725 2850);
DISPLAY INVISIBLE (-1725 2850);
FORCEPROP 1 LAST PATH I22
J 0
(-2052 2975);
DISPLAY 0.872340 (-2052 2975);
PAINT GREEN (-2052 2975);
DISPLAY INVISIBLE (-2052 2975);
FORCEADD TAP..1
(-1850 2875);
FORCEPROP 3 LASTPIN (-1900 2875) SIG_NAME P5E_CPU0_P2_RX_BUF_DN<1>
J 0
(-1890 2885);
DISPLAY 0.659574 (-1890 2885);
PAINT MONO (-1890 2885);
DISPLAY INVISIBLE (-1890 2885);
FORCEPROP 1 LASTPIN (-1900 2875) BN 1
J 0
(-1912 2883);
DISPLAY 0.680851 (-1912 2883);
PAINT GREEN (-1912 2883);
FORCEPROP 2 LAST CDS_LIB standard
J 0
(-1850 2875);
DISPLAY INVISIBLE (-1850 2875);
FORCEPROP 1 LAST BODY_TYPE PLUMBING
J 0
(-1850 2925);
DISPLAY 0.872340 (-1850 2925);
PAINT GREEN (-1850 2925);
DISPLAY INVISIBLE (-1850 2925);
FORCEPROP 1 LAST HDL_TAP TRUE
J 0
(-1525 2750);
DISPLAY 0.872340 (-1525 2750);
DISPLAY INVISIBLE (-1525 2750);
FORCEPROP 1 LAST PATH I23
J 0
(-1852 2875);
DISPLAY 0.872340 (-1852 2875);
PAINT GREEN (-1852 2875);
DISPLAY INVISIBLE (-1852 2875);
FORCEADD TAP..1
(-1850 3225);
FORCEPROP 3 LASTPIN (-1900 3225) SIG_NAME P5E_CPU0_P2_RX_BUF_DN<2>
J 0
(-1890 3235);
DISPLAY 0.659574 (-1890 3235);
PAINT MONO (-1890 3235);
DISPLAY INVISIBLE (-1890 3235);
FORCEPROP 1 LASTPIN (-1900 3225) BN 2
J 0
(-1912 3233);
DISPLAY 0.680851 (-1912 3233);
PAINT GREEN (-1912 3233);
FORCEPROP 2 LAST CDS_LIB standard
J 0
(-1850 3225);
DISPLAY INVISIBLE (-1850 3225);
FORCEPROP 1 LAST BODY_TYPE PLUMBING
J 0
(-1850 3275);
DISPLAY 0.872340 (-1850 3275);
PAINT GREEN (-1850 3275);
DISPLAY INVISIBLE (-1850 3275);
FORCEPROP 1 LAST HDL_TAP TRUE
J 0
(-1525 3100);
DISPLAY 0.872340 (-1525 3100);
DISPLAY INVISIBLE (-1525 3100);
FORCEPROP 1 LAST PATH I24
J 0
(-1852 3225);
DISPLAY 0.872340 (-1852 3225);
PAINT GREEN (-1852 3225);
DISPLAY INVISIBLE (-1852 3225);
FORCEADD TAP..1
(-2050 3325);
FORCEPROP 3 LASTPIN (-2100 3325) SIG_NAME P5E_CPU0_P2_RX_BUF_DP<2>
J 0
(-2090 3335);
DISPLAY 0.659574 (-2090 3335);
PAINT MONO (-2090 3335);
DISPLAY INVISIBLE (-2090 3335);
FORCEPROP 1 LASTPIN (-2100 3325) BN 2
J 0
(-2112 3333);
DISPLAY 0.680851 (-2112 3333);
PAINT GREEN (-2112 3333);
FORCEPROP 2 LAST CDS_LIB standard
J 0
(-2050 3325);
DISPLAY INVISIBLE (-2050 3325);
FORCEPROP 1 LAST BODY_TYPE PLUMBING
J 0
(-2050 3375);
DISPLAY 0.872340 (-2050 3375);
PAINT GREEN (-2050 3375);
DISPLAY INVISIBLE (-2050 3375);
FORCEPROP 1 LAST HDL_TAP TRUE
J 0
(-1725 3200);
DISPLAY 0.872340 (-1725 3200);
DISPLAY INVISIBLE (-1725 3200);
FORCEPROP 1 LAST PATH I25
J 0
(-2052 3325);
DISPLAY 0.872340 (-2052 3325);
PAINT GREEN (-2052 3325);
DISPLAY INVISIBLE (-2052 3325);
FORCEADD TAP..1
(-2050 3675);
FORCEPROP 3 LASTPIN (-2100 3675) SIG_NAME P5E_CPU0_P2_RX_BUF_DP<3>
J 0
(-2090 3685);
DISPLAY 0.659574 (-2090 3685);
PAINT MONO (-2090 3685);
DISPLAY INVISIBLE (-2090 3685);
FORCEPROP 1 LASTPIN (-2100 3675) BN 3
J 0
(-2112 3683);
DISPLAY 0.680851 (-2112 3683);
PAINT GREEN (-2112 3683);
FORCEPROP 2 LAST CDS_LIB standard
J 0
(-2050 3675);
DISPLAY INVISIBLE (-2050 3675);
FORCEPROP 1 LAST BODY_TYPE PLUMBING
J 0
(-2050 3725);
DISPLAY 0.872340 (-2050 3725);
PAINT GREEN (-2050 3725);
DISPLAY INVISIBLE (-2050 3725);
FORCEPROP 1 LAST HDL_TAP TRUE
J 0
(-1725 3550);
DISPLAY 0.872340 (-1725 3550);
DISPLAY INVISIBLE (-1725 3550);
FORCEPROP 1 LAST PATH I26
J 0
(-2052 3675);
DISPLAY 0.872340 (-2052 3675);
PAINT GREEN (-2052 3675);
DISPLAY INVISIBLE (-2052 3675);
FORCEADD TAP..1
(-1850 3575);
FORCEPROP 3 LASTPIN (-1900 3575) SIG_NAME P5E_CPU0_P2_RX_BUF_DN<3>
J 0
(-1890 3585);
DISPLAY 0.659574 (-1890 3585);
PAINT MONO (-1890 3585);
DISPLAY INVISIBLE (-1890 3585);
FORCEPROP 1 LASTPIN (-1900 3575) BN 3
J 0
(-1912 3583);
DISPLAY 0.680851 (-1912 3583);
PAINT GREEN (-1912 3583);
FORCEPROP 2 LAST CDS_LIB standard
J 0
(-1850 3575);
DISPLAY INVISIBLE (-1850 3575);
FORCEPROP 1 LAST BODY_TYPE PLUMBING
J 0
(-1850 3625);
DISPLAY 0.872340 (-1850 3625);
PAINT GREEN (-1850 3625);
DISPLAY INVISIBLE (-1850 3625);
FORCEPROP 1 LAST HDL_TAP TRUE
J 0
(-1525 3450);
DISPLAY 0.872340 (-1525 3450);
DISPLAY INVISIBLE (-1525 3450);
FORCEPROP 1 LAST PATH I27
J 0
(-1852 3575);
DISPLAY 0.872340 (-1852 3575);
PAINT GREEN (-1852 3575);
DISPLAY INVISIBLE (-1852 3575);
FORCEADD TAP..1
(-2050 4025);
FORCEPROP 3 LASTPIN (-2100 4025) SIG_NAME P5E_CPU0_P2_RX_BUF_DP<4>
J 0
(-2090 4035);
DISPLAY 0.659574 (-2090 4035);
PAINT MONO (-2090 4035);
DISPLAY INVISIBLE (-2090 4035);
FORCEPROP 1 LASTPIN (-2100 4025) BN 4
J 0
(-2112 4033);
DISPLAY 0.680851 (-2112 4033);
PAINT GREEN (-2112 4033);
FORCEPROP 2 LAST CDS_LIB standard
J 0
(-2050 4025);
DISPLAY INVISIBLE (-2050 4025);
FORCEPROP 1 LAST BODY_TYPE PLUMBING
J 0
(-2050 4075);
DISPLAY 0.872340 (-2050 4075);
PAINT GREEN (-2050 4075);
DISPLAY INVISIBLE (-2050 4075);
FORCEPROP 1 LAST HDL_TAP TRUE
J 0
(-1725 3900);
DISPLAY 0.872340 (-1725 3900);
DISPLAY INVISIBLE (-1725 3900);
FORCEPROP 1 LAST PATH I28
J 0
(-2052 4025);
DISPLAY 0.872340 (-2052 4025);
PAINT GREEN (-2052 4025);
DISPLAY INVISIBLE (-2052 4025);
FORCEADD TAP..1
(-1850 3925);
FORCEPROP 3 LASTPIN (-1900 3925) SIG_NAME P5E_CPU0_P2_RX_BUF_DN<4>
J 0
(-1890 3935);
DISPLAY 0.659574 (-1890 3935);
PAINT MONO (-1890 3935);
DISPLAY INVISIBLE (-1890 3935);
FORCEPROP 1 LASTPIN (-1900 3925) BN 4
J 0
(-1912 3933);
DISPLAY 0.680851 (-1912 3933);
PAINT GREEN (-1912 3933);
FORCEPROP 2 LAST CDS_LIB standard
J 0
(-1850 3925);
DISPLAY INVISIBLE (-1850 3925);
FORCEPROP 1 LAST BODY_TYPE PLUMBING
J 0
(-1850 3975);
DISPLAY 0.872340 (-1850 3975);
PAINT GREEN (-1850 3975);
DISPLAY INVISIBLE (-1850 3975);
FORCEPROP 1 LAST HDL_TAP TRUE
J 0
(-1525 3800);
DISPLAY 0.872340 (-1525 3800);
DISPLAY INVISIBLE (-1525 3800);
FORCEPROP 1 LAST PATH I29
J 0
(-1852 3925);
DISPLAY 0.872340 (-1852 3925);
PAINT GREEN (-1852 3925);
DISPLAY INVISIBLE (-1852 3925);
FORCEADD TAP..1
(-6300 2500);
FORCEPROP 3 LASTPIN (-6350 2500) SIG_NAME P5E_CPU0_P2_RX_BUF_DN<8>
J 0
(-6340 2510);
DISPLAY 0.659574 (-6340 2510);
PAINT MONO (-6340 2510);
DISPLAY INVISIBLE (-6340 2510);
FORCEPROP 1 LASTPIN (-6350 2500) BN 8
J 0
(-6362 2508);
DISPLAY 0.680851 (-6362 2508);
PAINT GREEN (-6362 2508);
FORCEPROP 2 LAST CDS_LIB standard
J 0
(-6300 2500);
DISPLAY INVISIBLE (-6300 2500);
FORCEPROP 1 LAST BODY_TYPE PLUMBING
J 0
(-6300 2550);
DISPLAY 0.872340 (-6300 2550);
PAINT GREEN (-6300 2550);
DISPLAY INVISIBLE (-6300 2550);
FORCEPROP 1 LAST HDL_TAP TRUE
J 0
(-5975 2375);
DISPLAY 0.872340 (-5975 2375);
DISPLAY INVISIBLE (-5975 2375);
FORCEPROP 1 LAST PATH I3
J 0
(-6302 2500);
DISPLAY 0.872340 (-6302 2500);
PAINT GREEN (-6302 2500);
DISPLAY INVISIBLE (-6302 2500);
FORCEADD TAP..1
(-2050 4375);
FORCEPROP 3 LASTPIN (-2100 4375) SIG_NAME P5E_CPU0_P2_RX_BUF_DP<5>
J 0
(-2090 4385);
DISPLAY 0.659574 (-2090 4385);
PAINT MONO (-2090 4385);
DISPLAY INVISIBLE (-2090 4385);
FORCEPROP 1 LASTPIN (-2100 4375) BN 5
J 0
(-2112 4383);
DISPLAY 0.680851 (-2112 4383);
PAINT GREEN (-2112 4383);
FORCEPROP 2 LAST CDS_LIB standard
J 0
(-2050 4375);
DISPLAY INVISIBLE (-2050 4375);
FORCEPROP 1 LAST BODY_TYPE PLUMBING
J 0
(-2050 4425);
DISPLAY 0.872340 (-2050 4425);
PAINT GREEN (-2050 4425);
DISPLAY INVISIBLE (-2050 4425);
FORCEPROP 1 LAST HDL_TAP TRUE
J 0
(-1725 4250);
DISPLAY 0.872340 (-1725 4250);
DISPLAY INVISIBLE (-1725 4250);
FORCEPROP 1 LAST PATH I30
J 0
(-2052 4375);
DISPLAY 0.872340 (-2052 4375);
PAINT GREEN (-2052 4375);
DISPLAY INVISIBLE (-2052 4375);
FORCEADD TAP..1
(-2050 4725);
FORCEPROP 3 LASTPIN (-2100 4725) SIG_NAME P5E_CPU0_P2_RX_BUF_DP<6>
J 0
(-2090 4735);
DISPLAY 0.659574 (-2090 4735);
PAINT MONO (-2090 4735);
DISPLAY INVISIBLE (-2090 4735);
FORCEPROP 1 LASTPIN (-2100 4725) BN 6
J 0
(-2112 4733);
DISPLAY 0.680851 (-2112 4733);
PAINT GREEN (-2112 4733);
FORCEPROP 2 LAST CDS_LIB standard
J 0
(-2050 4725);
DISPLAY INVISIBLE (-2050 4725);
FORCEPROP 1 LAST BODY_TYPE PLUMBING
J 0
(-2050 4775);
DISPLAY 0.872340 (-2050 4775);
PAINT GREEN (-2050 4775);
DISPLAY INVISIBLE (-2050 4775);
FORCEPROP 1 LAST HDL_TAP TRUE
J 0
(-1725 4600);
DISPLAY 0.872340 (-1725 4600);
DISPLAY INVISIBLE (-1725 4600);
FORCEPROP 1 LAST PATH I31
J 0
(-2052 4725);
DISPLAY 0.872340 (-2052 4725);
PAINT GREEN (-2052 4725);
DISPLAY INVISIBLE (-2052 4725);
FORCEADD TAP..1
(-1850 4275);
FORCEPROP 3 LASTPIN (-1900 4275) SIG_NAME P5E_CPU0_P2_RX_BUF_DN<5>
J 0
(-1890 4285);
DISPLAY 0.659574 (-1890 4285);
PAINT MONO (-1890 4285);
DISPLAY INVISIBLE (-1890 4285);
FORCEPROP 1 LASTPIN (-1900 4275) BN 5
J 0
(-1912 4283);
DISPLAY 0.680851 (-1912 4283);
PAINT GREEN (-1912 4283);
FORCEPROP 2 LAST CDS_LIB standard
J 0
(-1850 4275);
DISPLAY INVISIBLE (-1850 4275);
FORCEPROP 1 LAST BODY_TYPE PLUMBING
J 0
(-1850 4325);
DISPLAY 0.872340 (-1850 4325);
PAINT GREEN (-1850 4325);
DISPLAY INVISIBLE (-1850 4325);
FORCEPROP 1 LAST HDL_TAP TRUE
J 0
(-1525 4150);
DISPLAY 0.872340 (-1525 4150);
DISPLAY INVISIBLE (-1525 4150);
FORCEPROP 1 LAST PATH I32
J 0
(-1852 4275);
DISPLAY 0.872340 (-1852 4275);
PAINT GREEN (-1852 4275);
DISPLAY INVISIBLE (-1852 4275);
FORCEADD TAP..1
(-1850 4625);
FORCEPROP 3 LASTPIN (-1900 4625) SIG_NAME P5E_CPU0_P2_RX_BUF_DN<6>
J 0
(-1890 4635);
DISPLAY 0.659574 (-1890 4635);
PAINT MONO (-1890 4635);
DISPLAY INVISIBLE (-1890 4635);
FORCEPROP 1 LASTPIN (-1900 4625) BN 6
J 0
(-1912 4633);
DISPLAY 0.680851 (-1912 4633);
PAINT GREEN (-1912 4633);
FORCEPROP 2 LAST CDS_LIB standard
J 0
(-1850 4625);
DISPLAY INVISIBLE (-1850 4625);
FORCEPROP 1 LAST BODY_TYPE PLUMBING
J 0
(-1850 4675);
DISPLAY 0.872340 (-1850 4675);
PAINT GREEN (-1850 4675);
DISPLAY INVISIBLE (-1850 4675);
FORCEPROP 1 LAST HDL_TAP TRUE
J 0
(-1525 4500);
DISPLAY 0.872340 (-1525 4500);
DISPLAY INVISIBLE (-1525 4500);
FORCEPROP 1 LAST PATH I33
J 0
(-1852 4625);
DISPLAY 0.872340 (-1852 4625);
PAINT GREEN (-1852 4625);
DISPLAY INVISIBLE (-1852 4625);
FORCEADD TAP..1
(-2050 5075);
FORCEPROP 3 LASTPIN (-2100 5075) SIG_NAME P5E_CPU0_P2_RX_BUF_DP<7>
J 0
(-2090 5085);
DISPLAY 0.659574 (-2090 5085);
PAINT MONO (-2090 5085);
DISPLAY INVISIBLE (-2090 5085);
FORCEPROP 1 LASTPIN (-2100 5075) BN 7
J 0
(-2112 5083);
DISPLAY 0.680851 (-2112 5083);
PAINT GREEN (-2112 5083);
FORCEPROP 2 LAST CDS_LIB standard
J 0
(-2050 5075);
DISPLAY INVISIBLE (-2050 5075);
FORCEPROP 1 LAST BODY_TYPE PLUMBING
J 0
(-2050 5125);
DISPLAY 0.872340 (-2050 5125);
PAINT GREEN (-2050 5125);
DISPLAY INVISIBLE (-2050 5125);
FORCEPROP 1 LAST HDL_TAP TRUE
J 0
(-1725 4950);
DISPLAY 0.872340 (-1725 4950);
DISPLAY INVISIBLE (-1725 4950);
FORCEPROP 1 LAST PATH I34
J 0
(-2052 5075);
DISPLAY 0.872340 (-2052 5075);
PAINT GREEN (-2052 5075);
DISPLAY INVISIBLE (-2052 5075);
FORCEADD TAP..1
(-1850 4975);
FORCEPROP 3 LASTPIN (-1900 4975) SIG_NAME P5E_CPU0_P2_RX_BUF_DN<7>
J 0
(-1890 4985);
DISPLAY 0.659574 (-1890 4985);
PAINT MONO (-1890 4985);
DISPLAY INVISIBLE (-1890 4985);
FORCEPROP 1 LASTPIN (-1900 4975) BN 7
J 0
(-1912 4983);
DISPLAY 0.680851 (-1912 4983);
PAINT GREEN (-1912 4983);
FORCEPROP 2 LAST CDS_LIB standard
J 0
(-1850 4975);
DISPLAY INVISIBLE (-1850 4975);
FORCEPROP 1 LAST BODY_TYPE PLUMBING
J 0
(-1850 5025);
DISPLAY 0.872340 (-1850 5025);
PAINT GREEN (-1850 5025);
DISPLAY INVISIBLE (-1850 5025);
FORCEPROP 1 LAST HDL_TAP TRUE
J 0
(-1525 4850);
DISPLAY 0.872340 (-1525 4850);
DISPLAY INVISIBLE (-1525 4850);
FORCEPROP 1 LAST PATH I35
J 0
(-1852 4975);
DISPLAY 0.872340 (-1852 4975);
PAINT GREEN (-1852 4975);
DISPLAY INVISIBLE (-1852 4975);
FORCEADD OFFPAGE..1
R 2
(-825 5175);
FORCEPROP 2 LAST $XR0 116 
J 0
(-639 5175);
DISPLAY 0.638298 (-639 5175);
PAINT MONO (-639 5175);
FORCEPROP 2 LAST CDS_LIB standard
J 0
(-825 5175);
DISPLAY INVISIBLE (-825 5175);
FORCEPROP 1 LAST OFFPAGE TRUE
J 2
(-1150 5050);
DISPLAY 0.872340 (-1150 5050);
DISPLAY INVISIBLE (-1150 5050);
FORCEPROP 1 LAST COMMENT_BODY TRUE
J 2
(-950 5075);
DISPLAY 0.872340 (-950 5075);
PAINT GREEN (-950 5075);
DISPLAY INVISIBLE (-950 5075);
FORCEPROP 2 LAST PATH I36
J 0
(-650 5250);
DISPLAY 0.680851 (-650 5250);
DISPLAY INVISIBLE (-650 5250);
FORCEADD OFFPAGE..1
R 2
(-825 5100);
FORCEPROP 2 LAST $XR0 116 
J 0
(-639 5100);
DISPLAY 0.638298 (-639 5100);
PAINT MONO (-639 5100);
FORCEPROP 2 LAST CDS_LIB standard
J 0
(-825 5100);
DISPLAY INVISIBLE (-825 5100);
FORCEPROP 1 LAST OFFPAGE TRUE
J 2
(-1150 4975);
DISPLAY 0.872340 (-1150 4975);
DISPLAY INVISIBLE (-1150 4975);
FORCEPROP 1 LAST COMMENT_BODY TRUE
J 2
(-950 5000);
DISPLAY 0.872340 (-950 5000);
PAINT GREEN (-950 5000);
DISPLAY INVISIBLE (-950 5000);
FORCEPROP 2 LAST PATH I37
J 0
(-650 5175);
DISPLAY 0.680851 (-650 5175);
DISPLAY INVISIBLE (-650 5175);
FORCEADD PT5161LRS..2
(-3075 3825);
FORCEPROP 1 LAST LOCATION U6012
J 0
(-3425 5450);
DISPLAY 0.723404 (-3425 5450);
PAINT GREEN (-3425 5450);
FORCEPROP 0 LAST $SEC 2
J 0
(-3425 5600);
DISPLAY 0.680851 (-3425 5600);
PAINT MONO (-3425 5600);
DISPLAY INVISIBLE (-3425 5600);
FORCEPROP 0 LAST CDS_SEC 2
J 0
(-3425 5600);
DISPLAY 0.680851 (-3425 5600);
DISPLAY INVISIBLE (-3425 5600);
FORCEPROP 0 LASTPIN (-2625 4975) $PN CJ2
J 0
(-2615 4985);
DISPLAY 0.680851 (-2615 4985);
PAINT MONO (-2615 4985);
FORCEPROP 0 LASTPIN (-2625 4625) $PN CT2
J 0
(-2615 4635);
DISPLAY 0.680851 (-2615 4635);
PAINT MONO (-2615 4635);
FORCEPROP 0 LASTPIN (-2625 4275) $PN DC2
J 0
(-2615 4285);
DISPLAY 0.680851 (-2615 4285);
PAINT MONO (-2615 4285);
FORCEPROP 0 LASTPIN (-2625 3925) $PN DK2
J 0
(-2615 3935);
DISPLAY 0.680851 (-2615 3935);
PAINT MONO (-2615 3935);
FORCEPROP 0 LASTPIN (-2625 3575) $PN DU2
J 0
(-2615 3585);
DISPLAY 0.680851 (-2615 3585);
PAINT MONO (-2615 3585);
FORCEPROP 0 LASTPIN (-2625 3225) $PN ED2
J 0
(-2615 3235);
DISPLAY 0.680851 (-2615 3235);
PAINT MONO (-2615 3235);
FORCEPROP 0 LASTPIN (-2625 2875) $PN EL2
J 0
(-2615 2885);
DISPLAY 0.680851 (-2615 2885);
PAINT MONO (-2615 2885);
FORCEPROP 0 LASTPIN (-2625 2525) $PN EV2
J 0
(-2615 2535);
DISPLAY 0.680851 (-2615 2535);
PAINT MONO (-2615 2535);
FORCEPROP 0 LASTPIN (-2625 5075) $PN CL1
J 0
(-2615 5085);
DISPLAY 0.680851 (-2615 5085);
PAINT MONO (-2615 5085);
FORCEPROP 0 LASTPIN (-2625 4725) $PN CV1
J 0
(-2615 4735);
DISPLAY 0.680851 (-2615 4735);
PAINT MONO (-2615 4735);
FORCEPROP 0 LASTPIN (-2625 4375) $PN DE1
J 0
(-2615 4385);
DISPLAY 0.680851 (-2615 4385);
PAINT MONO (-2615 4385);
FORCEPROP 0 LASTPIN (-2625 4025) $PN DM1
J 0
(-2615 4035);
DISPLAY 0.680851 (-2615 4035);
PAINT MONO (-2615 4035);
FORCEPROP 0 LASTPIN (-2625 3675) $PN DW1
J 0
(-2615 3685);
DISPLAY 0.680851 (-2615 3685);
PAINT MONO (-2615 3685);
FORCEPROP 0 LASTPIN (-2625 3325) $PN EF1
J 0
(-2615 3335);
DISPLAY 0.680851 (-2615 3335);
PAINT MONO (-2615 3335);
FORCEPROP 0 LASTPIN (-2625 2975) $PN EN1
J 0
(-2615 2985);
DISPLAY 0.680851 (-2615 2985);
PAINT MONO (-2615 2985);
FORCEPROP 0 LASTPIN (-2625 2625) $PN EY1
J 0
(-2615 2635);
DISPLAY 0.680851 (-2615 2635);
PAINT MONO (-2615 2635);
FORCEPROP 2 LAST VALUE PT5161LRS
J 0
(-3425 5500);
DISPLAY 0.680851 (-3425 5500);
FORCEPROP 1 LAST MATERIAL IC
J 0
(-3425 5300);
DISPLAY 0.723404 (-3425 5300);
PAINT GREEN (-3425 5300);
FORCEPROP 2 LAST PART_TYPE SMLF
J 0
(-3425 5550);
DISPLAY 0.680851 (-3425 5550);
FORCEPROP 1 LAST NEEDS_NO_SIZE TRUE
J 0
(-3075 3825);
DISPLAY 0.723404 (-3075 3825);
PAINT GREEN (-3075 3825);
DISPLAY INVISIBLE (-3075 3825);
FORCEPROP 1 LAST CDS_LMAN_SYM_OUTLINE -350,1450,300,-1400
J 0
(-3075 3825);
DISPLAY 0.468085 (-3075 3825);
PAINT GREEN (-3075 3825);
DISPLAY INVISIBLE (-3075 3825);
FORCEPROP 2 LAST CDS_LIB pure_quanta
J 0
(-3075 3825);
DISPLAY INVISIBLE (-3075 3825);
FORCEPROP 1 LAST PATH I38
J 0
(-3075 3825);
DISPLAY 0.723404 (-3075 3825);
PAINT GREEN (-3075 3825);
DISPLAY INVISIBLE (-3075 3825);
FORCEPROP 1 LAST PART_NUMBER AJ051610U03
J 0
(-3425 5375);
DISPLAY 0.723404 (-3425 5375);
PAINT GREEN (-3425 5375);
DISPLAY INVISIBLE (-3425 5375);
FORCEADD TAP..1
(-6500 2950);
FORCEPROP 3 LASTPIN (-6550 2950) SIG_NAME P5E_CPU0_P2_RX_BUF_DP<9>
J 0
(-6540 2960);
DISPLAY 0.659574 (-6540 2960);
PAINT MONO (-6540 2960);
DISPLAY INVISIBLE (-6540 2960);
FORCEPROP 1 LASTPIN (-6550 2950) BN 9
J 0
(-6562 2958);
DISPLAY 0.680851 (-6562 2958);
PAINT GREEN (-6562 2958);
FORCEPROP 2 LAST CDS_LIB standard
J 0
(-6500 2950);
DISPLAY INVISIBLE (-6500 2950);
FORCEPROP 1 LAST BODY_TYPE PLUMBING
J 0
(-6500 3000);
DISPLAY 0.872340 (-6500 3000);
PAINT GREEN (-6500 3000);
DISPLAY INVISIBLE (-6500 3000);
FORCEPROP 1 LAST HDL_TAP TRUE
J 0
(-6175 2825);
DISPLAY 0.872340 (-6175 2825);
DISPLAY INVISIBLE (-6175 2825);
FORCEPROP 1 LAST PATH I4
J 0
(-6502 2950);
DISPLAY 0.872340 (-6502 2950);
PAINT GREEN (-6502 2950);
DISPLAY INVISIBLE (-6502 2950);
FORCEADD TAP..1
(-6300 2850);
FORCEPROP 3 LASTPIN (-6350 2850) SIG_NAME P5E_CPU0_P2_RX_BUF_DN<9>
J 0
(-6340 2860);
DISPLAY 0.659574 (-6340 2860);
PAINT MONO (-6340 2860);
DISPLAY INVISIBLE (-6340 2860);
FORCEPROP 1 LASTPIN (-6350 2850) BN 9
J 0
(-6362 2858);
DISPLAY 0.680851 (-6362 2858);
PAINT GREEN (-6362 2858);
FORCEPROP 2 LAST CDS_LIB standard
J 0
(-6300 2850);
DISPLAY INVISIBLE (-6300 2850);
FORCEPROP 1 LAST BODY_TYPE PLUMBING
J 0
(-6300 2900);
DISPLAY 0.872340 (-6300 2900);
PAINT GREEN (-6300 2900);
DISPLAY INVISIBLE (-6300 2900);
FORCEPROP 1 LAST HDL_TAP TRUE
J 0
(-5975 2725);
DISPLAY 0.872340 (-5975 2725);
DISPLAY INVISIBLE (-5975 2725);
FORCEPROP 1 LAST PATH I5
J 0
(-6302 2850);
DISPLAY 0.872340 (-6302 2850);
PAINT GREEN (-6302 2850);
DISPLAY INVISIBLE (-6302 2850);
FORCEADD TAP..1
(-6300 3200);
FORCEPROP 3 LASTPIN (-6350 3200) SIG_NAME P5E_CPU0_P2_RX_BUF_DN<10>
J 0
(-6340 3210);
DISPLAY 0.659574 (-6340 3210);
PAINT MONO (-6340 3210);
DISPLAY INVISIBLE (-6340 3210);
FORCEPROP 1 LASTPIN (-6350 3200) BN 10
J 0
(-6362 3208);
DISPLAY 0.680851 (-6362 3208);
PAINT GREEN (-6362 3208);
FORCEPROP 2 LAST CDS_LIB standard
J 0
(-6300 3200);
DISPLAY INVISIBLE (-6300 3200);
FORCEPROP 1 LAST BODY_TYPE PLUMBING
J 0
(-6300 3250);
DISPLAY 0.872340 (-6300 3250);
PAINT GREEN (-6300 3250);
DISPLAY INVISIBLE (-6300 3250);
FORCEPROP 1 LAST HDL_TAP TRUE
J 0
(-5975 3075);
DISPLAY 0.872340 (-5975 3075);
DISPLAY INVISIBLE (-5975 3075);
FORCEPROP 1 LAST PATH I6
J 0
(-6302 3200);
DISPLAY 0.872340 (-6302 3200);
PAINT GREEN (-6302 3200);
DISPLAY INVISIBLE (-6302 3200);
FORCEADD TAP..1
(-6500 3300);
FORCEPROP 3 LASTPIN (-6550 3300) SIG_NAME P5E_CPU0_P2_RX_BUF_DP<10>
J 0
(-6540 3310);
DISPLAY 0.659574 (-6540 3310);
PAINT MONO (-6540 3310);
DISPLAY INVISIBLE (-6540 3310);
FORCEPROP 1 LASTPIN (-6550 3300) BN 10
J 0
(-6562 3308);
DISPLAY 0.680851 (-6562 3308);
PAINT GREEN (-6562 3308);
FORCEPROP 2 LAST CDS_LIB standard
J 0
(-6500 3300);
DISPLAY INVISIBLE (-6500 3300);
FORCEPROP 1 LAST BODY_TYPE PLUMBING
J 0
(-6500 3350);
DISPLAY 0.872340 (-6500 3350);
PAINT GREEN (-6500 3350);
DISPLAY INVISIBLE (-6500 3350);
FORCEPROP 1 LAST HDL_TAP TRUE
J 0
(-6175 3175);
DISPLAY 0.872340 (-6175 3175);
DISPLAY INVISIBLE (-6175 3175);
FORCEPROP 1 LAST PATH I7
J 0
(-6502 3300);
DISPLAY 0.872340 (-6502 3300);
PAINT GREEN (-6502 3300);
DISPLAY INVISIBLE (-6502 3300);
FORCEADD TAP..1
(-6300 3550);
FORCEPROP 3 LASTPIN (-6350 3550) SIG_NAME P5E_CPU0_P2_RX_BUF_DN<11>
J 0
(-6340 3560);
DISPLAY 0.659574 (-6340 3560);
PAINT MONO (-6340 3560);
DISPLAY INVISIBLE (-6340 3560);
FORCEPROP 1 LASTPIN (-6350 3550) BN 11
J 0
(-6362 3558);
DISPLAY 0.680851 (-6362 3558);
PAINT GREEN (-6362 3558);
FORCEPROP 2 LAST CDS_LIB standard
J 0
(-6300 3550);
DISPLAY INVISIBLE (-6300 3550);
FORCEPROP 1 LAST BODY_TYPE PLUMBING
J 0
(-6300 3600);
DISPLAY 0.872340 (-6300 3600);
PAINT GREEN (-6300 3600);
DISPLAY INVISIBLE (-6300 3600);
FORCEPROP 1 LAST HDL_TAP TRUE
J 0
(-5975 3425);
DISPLAY 0.872340 (-5975 3425);
DISPLAY INVISIBLE (-5975 3425);
FORCEPROP 1 LAST PATH I8
J 0
(-6302 3550);
DISPLAY 0.872340 (-6302 3550);
PAINT GREEN (-6302 3550);
DISPLAY INVISIBLE (-6302 3550);
FORCEADD TAP..1
(-6500 3650);
FORCEPROP 3 LASTPIN (-6550 3650) SIG_NAME P5E_CPU0_P2_RX_BUF_DP<11>
J 0
(-6540 3660);
DISPLAY 0.659574 (-6540 3660);
PAINT MONO (-6540 3660);
DISPLAY INVISIBLE (-6540 3660);
FORCEPROP 1 LASTPIN (-6550 3650) BN 11
J 0
(-6562 3658);
DISPLAY 0.680851 (-6562 3658);
PAINT GREEN (-6562 3658);
FORCEPROP 2 LAST CDS_LIB standard
J 0
(-6500 3650);
DISPLAY INVISIBLE (-6500 3650);
FORCEPROP 1 LAST BODY_TYPE PLUMBING
J 0
(-6500 3700);
DISPLAY 0.872340 (-6500 3700);
PAINT GREEN (-6500 3700);
DISPLAY INVISIBLE (-6500 3700);
FORCEPROP 1 LAST HDL_TAP TRUE
J 0
(-6175 3525);
DISPLAY 0.872340 (-6175 3525);
DISPLAY INVISIBLE (-6175 3525);
FORCEPROP 1 LAST PATH I9
J 0
(-6502 3650);
DISPLAY 0.872340 (-6502 3650);
PAINT GREEN (-6502 3650);
DISPLAY INVISIBLE (-6502 3650);
FORCEADD QUANTA_TITLE_BLOCK_C..1
(0 0);
FORCEPROP 0 LAST CDS_CON_LAST_MODIFIED Thu Sep 14 16:12:52 2023
J 0
(-1885 15);
DISPLAY INVISIBLE (-1885 15);
FORCEPROP 1 LAST CUSTOM_TXT_CDS <CON_LAST_MODIFIED>
J 0
(-1885 15);
DISPLAY 0.978723 (-1885 15);
FORCEPROP 2 LAST CUSTOM_TXT_CDS <XR_PAGE_TITLE>
J 0
(-7890 5250);
DISPLAY 0.638298 (-7890 5250);
PAINT PINK (-7890 5250);
DISPLAY INVISIBLE (-7890 5250);
FORCEPROP 1 LAST CUSTOM_TXT_CDS <NAME_2>
J 0
(-3175 50);
FORCEPROP 1 LAST CUSTOM_TXT_CDS <NAME_1>
J 0
(-3175 175);
FORCEPROP 1 LAST CUSTOM_TXT_CDS <Q_NUMBER>
J 0
(-1403 103);
DISPLAY 1.212766 (-1403 103);
FORCEPROP 1 LAST CUSTOM_TXT_CDS <Q_PROJ>
J 0
(-2382 102);
DISPLAY 1.212766 (-2382 102);
FORCEPROP 1 LAST CUSTOM_TXT_CDS <Q_REV>
J 0
(-184 103);
DISPLAY 1.212766 (-184 103);
FORCEPROP 1 LAST CUSTOM_TXT_CDS <CON_PAGE_NUM> OF <CON_TOTAL_PAGES>
J 0
(-446 18);
DISPLAY 0.978723 (-446 18);
FORCEPROP 1 LAST Q_TITLE RETIMER_CPU0_P2(3)
J 0
(-9366 26);
DISPLAY 2.446809 (-9366 26);
PAINT GREEN (-9366 26);
FORCEPROP 2 LAST CDS_LIB pure_quanta
J 0
(0 0);
DISPLAY INVISIBLE (0 0);
FORCEPROP 1 LAST CDS_LMAN_SYM_OUTLINE -9475,6775,100,-125
J 0
(0 0);
DISPLAY 0.468085 (0 0);
PAINT GREEN (0 0);
DISPLAY INVISIBLE (0 0);
FORCEPROP 2 LAST PAGE_BORDER TRUE
J 0
(-7890 5250);
DISPLAY 0.638298 (-7890 5250);
PAINT PINK (-7890 5250);
DISPLAY INVISIBLE (-7890 5250);
FORCEPROP 2 LAST CDS_XR_PAGE_TITLE CR-297 : @T6G_MB_LIB.T6G(SCH_1):PAGE297
J 0
(-7890 5250);
DISPLAY 0.638298 (-7890 5250);
PAINT PINK (-7890 5250);
DISPLAY INVISIBLE (-7890 5250);
FORCEPROP 1 LAST Q_DEPT BU9
J 1
(-3763 49);
DISPLAY 1.957447 (-3763 49);
PAINT GREEN (-3763 49);
DISPLAY INVISIBLE (-3763 49);
FORCEPROP 1 LAST COMMENT_BODY TRUE
J 0
(12 -13);
DISPLAY 0.978723 (12 -13);
PAINT GREEN (12 -13);
DISPLAY INVISIBLE (12 -13);
WIRE 17 -1 (-6250 3575)(-6250 3225);
WIRE 17 -1 (-6250 3575)(-6250 3925);
WIRE 17 -1 (-6250 3225)(-6250 2875);
WIRE 17 -1 (-6250 2875)(-6250 2525);
WIRE 17 -1 (-6250 4275)(-6250 3925);
WIRE 17 -1 (-6250 4625)(-6250 4275);
WIRE 17 -1 (-6250 4975)(-6250 4625);
WIRE 17 -1 (-6250 5075)(-6250 4975);
WIRE 17 -1 (-6250 5075)(-5325 5075);
FORCEPROP 2 LAST SIG_NAME P5E_CPU0_P2_RX_BUF_DN<15:8>
J 0
(-6185 5085);
DISPLAY 0.680851 (-6185 5085);
PAINT WHITE (-6185 5085);
WIRE 17 -1 (-6450 3325)(-6450 2975);
WIRE 17 -1 (-6450 3675)(-6450 3325);
WIRE 17 -1 (-6450 2975)(-6450 2625);
WIRE 17 -1 (-6450 3675)(-6450 4025);
WIRE 17 -1 (-6450 4375)(-6450 4025);
WIRE 17 -1 (-6450 4725)(-6450 4375);
WIRE 17 -1 (-6450 5075)(-6450 4725);
WIRE 17 -1 (-6450 5150)(-6450 5075);
WIRE 17 -1 (-6450 5150)(-5325 5150);
FORCEPROP 2 LAST SIG_NAME P5E_CPU0_P2_RX_BUF_DP<15:8>
J 0
(-6185 5160);
DISPLAY 0.680851 (-6185 5160);
PAINT WHITE (-6185 5160);
WIRE 17 -1 (-1800 2900)(-1800 2550);
WIRE 17 -1 (-1800 3250)(-1800 2900);
WIRE 17 -1 (-1800 3600)(-1800 3250);
WIRE 17 -1 (-1800 3600)(-1800 3950);
WIRE 17 -1 (-1800 4300)(-1800 3950);
WIRE 17 -1 (-1800 4650)(-1800 4300);
WIRE 17 -1 (-1800 5000)(-1800 4650);
WIRE 17 -1 (-1800 5100)(-1800 5000);
WIRE 17 -1 (-1800 5100)(-875 5100);
FORCEPROP 2 LAST SIG_NAME P5E_CPU0_P2_RX_BUF_DN<7:0>
J 0
(-1735 5110);
DISPLAY 0.680851 (-1735 5110);
PAINT WHITE (-1735 5110);
WIRE 17 -1 (-2000 3350)(-2000 3000);
WIRE 17 -1 (-2000 3700)(-2000 3350);
WIRE 17 -1 (-2000 3000)(-2000 2650);
WIRE 17 -1 (-2000 3700)(-2000 4050);
WIRE 17 -1 (-2000 4400)(-2000 4050);
WIRE 17 -1 (-2000 4750)(-2000 4400);
WIRE 17 -1 (-2000 5100)(-2000 4750);
WIRE 17 -1 (-2000 5175)(-2000 5100);
WIRE 17 -1 (-2000 5175)(-875 5175);
FORCEPROP 2 LAST SIG_NAME P5E_CPU0_P2_RX_BUF_DP<7:0>
J 0
(-1735 5185);
DISPLAY 0.680851 (-1735 5185);
PAINT WHITE (-1735 5185);
WIRE 16 -1 (-7075 4950)(-6350 4950);
WIRE 16 -1 (-7075 5050)(-6550 5050);
WIRE 16 -1 (-7075 4700)(-6550 4700);
WIRE 16 -1 (-7075 4600)(-6350 4600);
WIRE 16 -1 (-7075 4350)(-6550 4350);
WIRE 16 -1 (-7075 3900)(-6350 3900);
WIRE 16 -1 (-7075 3650)(-6550 3650);
WIRE 16 -1 (-7075 3550)(-6350 3550);
WIRE 16 -1 (-7075 3300)(-6550 3300);
WIRE 16 -1 (-2625 4375)(-2100 4375);
WIRE 16 -1 (-2625 4275)(-1900 4275);
WIRE 16 -1 (-2625 3925)(-1900 3925);
WIRE 16 -1 (-2625 4975)(-1900 4975);
WIRE 16 -1 (-2625 2875)(-1900 2875);
WIRE 16 -1 (-2625 2625)(-2100 2625);
WIRE 16 -1 (-2625 4625)(-1900 4625);
WIRE 16 -1 (-7075 4250)(-6350 4250);
WIRE 16 -1 (-7075 4000)(-6550 4000);
WIRE 16 -1 (-7075 2850)(-6350 2850);
WIRE 16 -1 (-7075 2600)(-6550 2600);
WIRE 16 -1 (-2625 4725)(-2100 4725);
WIRE 16 -1 (-7075 2500)(-6350 2500);
WIRE 16 -1 (-2625 3675)(-2100 3675);
WIRE 16 -1 (-2625 3575)(-1900 3575);
WIRE 16 -1 (-2625 5075)(-2100 5075);
WIRE 16 -1 (-2625 4025)(-2100 4025);
WIRE 16 -1 (-2625 3225)(-1900 3225);
WIRE 16 -1 (-2625 3325)(-2100 3325);
WIRE 16 -1 (-2625 2975)(-2100 2975);
WIRE 16 -1 (-2625 2525)(-1900 2525);
WIRE 16 -1 (-7075 2950)(-6550 2950);
WIRE 16 -1 (-7075 3200)(-6350 3200);
FORCENOTE
EXAMAX TO RETIMER
(-3350 1650) 0;
DISPLAY LEFT (-3350 1650);
DISPLAY 3.148936 (-3350 1650);
FORCENOTE
EXAMAX TO RETIMER
(-7900 1675) 0;
DISPLAY LEFT (-7900 1675);
DISPLAY 3.148936 (-7900 1675);
FORCENOTE
P5E_CPU0_P2_RX_BUF_DP/DN <0-15> LANE REVERSAL
(-9075 6250) 0;
DISPLAY LEFT (-9075 6250);
DISPLAY 2.000000 (-9075 6250);
QUIT
